(kicad_pcb
	(version 20241229)
	(generator "pcbnew")
	(generator_version "9.0")
	(general
		(thickness 1.6)
		(legacy_teardrops no)
	)
	(paper "A4")
	(title_block
		(title "GMSL Deserializer")
		(date "2025-10-09")
		(rev "1.0.4")
		(company "Antmicro Ltd")
		(comment 1 "www.antmicro.com")
		(comment 9 "footprints 186-189 of 235")
	)
	(layers
		(0 "F.Cu" signal)
		(4 "In1.Cu" power)
		(6 "In2.Cu" power)
		(2 "B.Cu" signal)
		(9 "F.Adhes" user "F.Adhesive")
		(11 "B.Adhes" user "B.Adhesive")
		(13 "F.Paste" user)
		(15 "B.Paste" user)
		(5 "F.SilkS" user "F.Silkscreen")
		(7 "B.SilkS" user "B.Silkscreen")
		(1 "F.Mask" user)
		(3 "B.Mask" user)
		(17 "Dwgs.User" user "User.Drawings")
		(19 "Cmts.User" user "User.Comments")
		(21 "Eco1.User" user "User.Eco1")
		(23 "Eco2.User" user "User.Eco2")
		(25 "Edge.Cuts" user)
		(27 "Margin" user)
		(31 "F.CrtYd" user "F.Courtyard")
		(29 "B.CrtYd" user "B.Courtyard")
		(35 "F.Fab" user)
		(33 "B.Fab" user)
	)
	(footprint "antmicro-footprints:R_0402_1005Metric"
		(layer "B.Cu")
		(at 133.858 82.702 180)
		(descr "Resistor SMD 0402")
		(tags "resistor SMD 0402")
		(property "Reference" "R52"
			(at 1.143 0.406 0)
			(layer "B.SilkS")
			(effects
				(font
					(size 0.7 0.7)
					(thickness 0.15)
				)
				(justify right bottom mirror)
			)
		)
		(property "Value" "R_0R_0402"
			(at -1.011843 -1.772047 0)
			(layer "B.Fab")
			(effects
				(font
					(size 0.7 0.7)
					(thickness 0.15)
				)
				(justify left bottom mirror)
			)
		)
		(property "Datasheet" "https://industrial.panasonic.com/cdbs/www-data/pdf/RDA0000/AOA0000C301.pdf"
			(at 0 0 180)
			(layer "F.Fab")
			(hide yes)
			(effects
				(font
					(size 1.27 1.27)
					(thickness 0.15)
				)
			)
		)
		(property "Description" "SMD Chip Resistor, Jumper, 0 ohm, 100 mW, 0402 [1005 Metric], Thick Film, General Purpose"
			(at 0 0 180)
			(layer "F.Fab")
			(hide yes)
			(effects
				(font
					(size 1.27 1.27)
					(thickness 0.15)
				)
			)
		)
		(property "Author" "Antmicro"
			(at 267.716 165.404 0)
			(layer "B.Fab")
			(hide yes)
			(effects
				(font
					(size 1 1)
					(thickness 0.15)
				)
				(justify mirror)
			)
		)
		(property "Current" "1A"
			(at 267.716 165.404 0)
			(layer "B.Fab")
			(hide yes)
			(effects
				(font
					(size 1 1)
					(thickness 0.15)
				)
				(justify mirror)
			)
		)
		(property "License" "Apache-2.0"
			(at 267.716 165.404 0)
			(layer "B.Fab")
			(hide yes)
			(effects
				(font
					(size 1 1)
					(thickness 0.15)
				)
				(justify mirror)
			)
		)
		(property "MPN" "ERJ2GE0R00X"
			(at 267.716 165.404 0)
			(layer "B.Fab")
			(hide yes)
			(effects
				(font
					(size 1 1)
					(thickness 0.15)
				)
				(justify mirror)
			)
		)
		(property "Manufacturer" "Panasonic"
			(at 267.716 165.404 0)
			(layer "B.Fab")
			(hide yes)
			(effects
				(font
					(size 1 1)
					(thickness 0.15)
				)
				(justify mirror)
			)
		)
		(property "Tolerance" ""
			(at 267.716 165.404 0)
			(layer "B.Fab")
			(hide yes)
			(effects
				(font
					(size 1 1)
					(thickness 0.15)
				)
				(justify mirror)
			)
		)
		(property "Val" "0R"
			(at 267.716 165.404 0)
			(layer "B.Fab")
			(hide yes)
			(effects
				(font
					(size 1 1)
					(thickness 0.15)
				)
				(justify mirror)
			)
		)
		(sheetname "/Deserializer/")
		(sheetfile "deserializer.kicad_sch")
		(attr smd)
		(fp_rect
			(start -0.925 0.47)
			(end 0.925 -0.47)
			(stroke
				(width 0.05)
				(type default)
			)
			(fill no)
			(layer "B.CrtYd")
		)
		(fp_rect
			(start -0.5 0.25)
			(end 0.5 -0.25)
			(stroke
				(width 0.15)
				(type solid)
			)
			(fill no)
			(layer "B.Fab")
		)
		(pad "1" smd roundrect
			(at -0.48 0 180)
			(size 0.59 0.64)
			(layers "B.Cu" "B.Mask" "B.Paste")
			(roundrect_rratio 0.25)
			(net 26 "/Deserializer/VDD_1.8V")
			(pintype "passive")
		)
		(pad "2" smd roundrect
			(at 0.48 0 180)
			(size 0.59 0.64)
			(layers "B.Cu" "B.Mask" "B.Paste")
			(roundrect_rratio 0.25)
			(net 3 "+1V8")
			(pintype "passive")
		)
	)
	(footprint "antmicro-footprints:TP_SMD_0.75mm"
		(layer "B.Cu")
		(at 144.78 97.89 180)
		(property "Reference" "TP17"
			(at 0 0.6 0)
			(layer "B.SilkS")
			(hide yes)
			(effects
				(font
					(size 0.7 0.7)
					(thickness 0.15)
				)
				(justify left bottom mirror)
			)
		)
		(property "Value" "TP_0.75mm_SMD"
			(at 0 -1.2 0)
			(layer "B.Fab")
			(effects
				(font
					(size 0.7 0.7)
					(thickness 0.15)
				)
				(justify left bottom mirror)
			)
		)
		(property "Description" "SMT test point"
			(at 0 0 0)
			(layer "B.Fab")
			(hide yes)
			(effects
				(font
					(size 1.27 1.27)
					(thickness 0.15)
				)
				(justify mirror)
			)
		)
		(property "MPN" ""
			(at 0 0 0)
			(unlocked yes)
			(layer "B.Fab")
			(hide yes)
			(effects
				(font
					(size 1 1)
					(thickness 0.15)
				)
				(justify mirror)
			)
		)
		(property "Manufacturer" ""
			(at 0 0 0)
			(unlocked yes)
			(layer "B.Fab")
			(hide yes)
			(effects
				(font
					(size 1 1)
					(thickness 0.15)
				)
				(justify mirror)
			)
		)
		(property "Author" "Antmicro"
			(at 0 0 0)
			(unlocked yes)
			(layer "B.Fab")
			(hide yes)
			(effects
				(font
					(size 1 1)
					(thickness 0.15)
				)
				(justify mirror)
			)
		)
		(property "License" "Apache-2.0"
			(at 0 0 0)
			(unlocked yes)
			(layer "B.Fab")
			(hide yes)
			(effects
				(font
					(size 1 1)
					(thickness 0.15)
				)
				(justify mirror)
			)
		)
		(sheetname "/Power/")
		(sheetfile "power.kicad_sch")
		(attr exclude_from_pos_files)
		(fp_circle
			(center 0 0)
			(end 0.475 0)
			(stroke
				(width 0.05)
				(type default)
			)
			(fill no)
			(layer "B.CrtYd")
		)
		(fp_text user "${REFERENCE}"
			(at -0.4 -2.7 0)
			(layer "B.Fab")
			(effects
				(font
					(size 0.7 0.7)
					(thickness 0.15)
				)
				(justify left bottom mirror)
			)
		)
		(fp_text user "Author: Antmicro"
			(at -0.4 -3.901 0)
			(layer "B.Fab")
			(effects
				(font
					(size 0.7 0.7)
					(thickness 0.15)
				)
				(justify left bottom mirror)
			)
		)
		(fp_text user "License: Apache-2.0"
			(at -0.4 -5.101 0)
			(layer "B.Fab")
			(effects
				(font
					(size 0.7 0.7)
					(thickness 0.15)
				)
				(justify left bottom mirror)
			)
		)
		(pad "1" smd circle
			(at 0 0 180)
			(size 0.75 0.75)
			(layers "B.Cu" "B.Mask")
			(net 10 "/Power/OUT_1V8")
			(pinfunction "1")
			(pintype "passive")
		)
	)
	(footprint "antmicro-footprints:Spacer_Drill3.7mm_H6mm_9774060151R"
		(layer "B.Cu")
		(at 184.372 93.068 180)
		(descr "Spacer M=3 h=36mm fi=5.1mm")
		(property "Reference" "H1"
			(at 0 3.2 0)
			(layer "B.SilkS")
			(effects
				(font
					(size 0.7 0.7)
					(thickness 0.15)
				)
				(justify left bottom mirror)
			)
		)
		(property "Value" "Spacer_Drill3.7mm_H6mm_9774060151R"
			(at 0 -4 0)
			(layer "B.Fab")
			(effects
				(font
					(size 0.7 0.7)
					(thickness 0.15)
				)
				(justify left bottom mirror)
			)
		)
		(property "Datasheet" "https://www.we-online.com/components/products/datasheet/9774060151R.pdf"
			(at 0 0 180)
			(layer "F.Fab")
			(hide yes)
			(effects
				(font
					(size 1.27 1.27)
					(thickness 0.15)
				)
			)
		)
		(property "Description" "Spacer, SMT, Non Stop, Steel, Swage Round, 5.1 mm x 6 mm, M2.5 Thread, WA-SMSI Series"
			(at 0 0 180)
			(layer "F.Fab")
			(hide yes)
			(effects
				(font
					(size 1.27 1.27)
					(thickness 0.15)
				)
			)
		)
		(property "Author" "Antmicro"
			(at 368.744 186.136 0)
			(layer "B.Fab")
			(hide yes)
			(effects
				(font
					(size 1 1)
					(thickness 0.15)
				)
				(justify mirror)
			)
		)
		(property "License" "Apache-2.0"
			(at 368.744 186.136 0)
			(layer "B.Fab")
			(hide yes)
			(effects
				(font
					(size 1 1)
					(thickness 0.15)
				)
				(justify mirror)
			)
		)
		(property "MPN" "9774060151R"
			(at 368.744 186.136 0)
			(layer "B.Fab")
			(hide yes)
			(effects
				(font
					(size 1 1)
					(thickness 0.15)
				)
				(justify mirror)
			)
		)
		(property "Manufacturer" "Würth Elektronik"
			(at 368.744 186.136 0)
			(layer "B.Fab")
			(hide yes)
			(effects
				(font
					(size 1 1)
					(thickness 0.15)
				)
				(justify mirror)
			)
		)
		(sheetname "/")
		(sheetfile "gmsl-deserializer.kicad_sch")
		(solder_paste_margin_ratio -1)
		(attr smd)
		(fp_circle
			(center 0 0)
			(end 3.05 0)
			(stroke
				(width 0.05)
				(type solid)
			)
			(fill no)
			(layer "B.CrtYd")
		)
		(fp_circle
			(center 0 0)
			(end 2.6 0)
			(stroke
				(width 0.15)
				(type solid)
			)
			(fill no)
			(layer "B.Fab")
		)
		(pad "" smd custom
			(at -1.7 -1.7 90)
			(size 0.62 0.62)
			(layers "B.Paste")
			(thermal_bridge_angle 90)
			(options
				(clearance outline)
				(anchor circle)
			)
			(primitives
				(gr_arc
					(start 1.266786 0.24747)
					(mid 0.285453 -0.29439)
					(end -0.250195 -1.279127)
					(width 0.2)
				)
				(gr_arc
					(start 1.259603 0.339191)
					(mid 0.218448 -0.232561)
					(end -0.34334 -1.279127)
					(width 0.2)
				)
				(gr_arc
					(start 1.255279 0.431435)
					(mid 0.152481 -0.169693)
					(end -0.436309 -1.279127)
					(width 0.2)
				)
				(gr_arc
					(start 1.253811 0.524161)
					(mid 0.087542 -0.105784)
					(end -0.529126 -1.279127)
					(width 0.2)
				)
				(gr_arc
					(start 1.275473 0.621136)
					(mid 0.0309 -0.033527)
					(end -0.621807 -1.279127)
					(width 0.2)
				)
				(gr_arc
					(start 1.263664 0.711602)
					(mid -0.037759 0.026651)
					(end -0.71437 -1.279127)
					(width 0.2)
				)
				(gr_arc
					(start 1.253435 0.802342)
					(mid -0.105837 0.087395)
					(end -0.806826 -1.279127)
					(width 0.2)
				)
				(gr_arc
					(start 1.267475 0.897258)
					(mid -0.165236 0.156885)
					(end -0.899187 -1.279127)
					(width 0.2)
				)
				(gr_arc
					(start 1.270645 0.990112)
					(mid -0.228522 0.222449)
					(end -0.991463 -1.279127)
					(width 0.2)
				)
				(gr_arc
					(start 1.266278 1.081674)
					(mid -0.294507 0.285313)
					(end -1.083663 -1.279127)
					(width 0.2)
				)
				(gr_line
					(start 1.279127 0.250195)
					(end 1.279127 1.083663)
					(width 0.2)
				)
				(gr_line
					(start -0.250195 -1.279127)
					(end -1.083663 -1.279127)
					(width 0.2)
				)
			)
		)
		(pad "" smd custom
			(at -1.7 1.7 180)
			(size 0.62 0.62)
			(layers "B.Paste")
			(thermal_bridge_angle 90)
			(options
				(clearance outline)
				(anchor circle)
			)
			(primitives
				(gr_arc
					(start 1.266786 0.24747)
					(mid 0.285453 -0.29439)
					(end -0.250195 -1.279127)
					(width 0.2)
				)
				(gr_arc
					(start 1.259603 0.339191)
					(mid 0.218448 -0.232561)
					(end -0.34334 -1.279127)
					(width 0.2)
				)
				(gr_arc
					(start 1.255279 0.431435)
					(mid 0.152481 -0.169693)
					(end -0.436309 -1.279127)
					(width 0.2)
				)
				(gr_arc
					(start 1.253811 0.524161)
					(mid 0.087542 -0.105784)
					(end -0.529126 -1.279127)
					(width 0.2)
				)
				(gr_arc
					(start 1.275473 0.621136)
					(mid 0.0309 -0.033527)
					(end -0.621807 -1.279127)
					(width 0.2)
				)
				(gr_arc
					(start 1.263664 0.711602)
					(mid -0.037759 0.026651)
					(end -0.71437 -1.279127)
					(width 0.2)
				)
				(gr_arc
					(start 1.253435 0.802342)
					(mid -0.105837 0.087395)
					(end -0.806826 -1.279127)
					(width 0.2)
				)
				(gr_arc
					(start 1.267475 0.897258)
					(mid -0.165236 0.156885)
					(end -0.899187 -1.279127)
					(width 0.2)
				)
				(gr_arc
					(start 1.270645 0.990112)
					(mid -0.228522 0.222449)
					(end -0.991463 -1.279127)
					(width 0.2)
				)
				(gr_arc
					(start 1.266278 1.081674)
					(mid -0.294507 0.285313)
					(end -1.083663 -1.279127)
					(width 0.2)
				)
				(gr_line
					(start 1.279127 0.250195)
					(end 1.279127 1.083663)
					(width 0.2)
				)
				(gr_line
					(start -0.250195 -1.279127)
					(end -1.083663 -1.279127)
					(width 0.2)
				)
			)
		)
		(pad "" smd custom
			(at 1.7 -1.7)
			(size 0.62 0.62)
			(layers "B.Paste")
			(thermal_bridge_angle 90)
			(options
				(clearance outline)
				(anchor circle)
			)
			(primitives
				(gr_arc
					(start 1.266786 0.24747)
					(mid 0.285453 -0.29439)
					(end -0.250195 -1.279127)
					(width 0.2)
				)
				(gr_arc
					(start 1.259603 0.339191)
					(mid 0.218448 -0.232561)
					(end -0.34334 -1.279127)
					(width 0.2)
				)
				(gr_arc
					(start 1.255279 0.431435)
					(mid 0.152481 -0.169693)
					(end -0.436309 -1.279127)
					(width 0.2)
				)
				(gr_arc
					(start 1.253811 0.524161)
					(mid 0.087542 -0.105784)
					(end -0.529126 -1.279127)
					(width 0.2)
				)
				(gr_arc
					(start 1.275473 0.621136)
					(mid 0.0309 -0.033527)
					(end -0.621807 -1.279127)
					(width 0.2)
				)
				(gr_arc
					(start 1.263664 0.711602)
					(mid -0.037759 0.026651)
					(end -0.71437 -1.279127)
					(width 0.2)
				)
				(gr_arc
					(start 1.253435 0.802342)
					(mid -0.105837 0.087395)
					(end -0.806826 -1.279127)
					(width 0.2)
				)
				(gr_arc
					(start 1.267475 0.897258)
					(mid -0.165236 0.156885)
					(end -0.899187 -1.279127)
					(width 0.2)
				)
				(gr_arc
					(start 1.270645 0.990112)
					(mid -0.228522 0.222449)
					(end -0.991463 -1.279127)
					(width 0.2)
				)
				(gr_arc
					(start 1.266278 1.081674)
					(mid -0.294507 0.285313)
					(end -1.083663 -1.279127)
					(width 0.2)
				)
				(gr_line
					(start 1.279127 0.250195)
					(end 1.279127 1.083663)
					(width 0.2)
				)
				(gr_line
					(start -0.250195 -1.279127)
					(end -1.083663 -1.279127)
					(width 0.2)
				)
			)
		)
		(pad "" smd custom
			(at 1.7 1.7 270)
			(size 0.62 0.62)
			(layers "B.Paste")
			(thermal_bridge_angle 90)
			(options
				(clearance outline)
				(anchor circle)
			)
			(primitives
				(gr_arc
					(start 1.266786 0.24747)
					(mid 0.285453 -0.29439)
					(end -0.250195 -1.279127)
					(width 0.2)
				)
				(gr_arc
					(start 1.259603 0.339191)
					(mid 0.218448 -0.232561)
					(end -0.34334 -1.279127)
					(width 0.2)
				)
				(gr_arc
					(start 1.255279 0.431435)
					(mid 0.152481 -0.169693)
					(end -0.436309 -1.279127)
					(width 0.2)
				)
				(gr_arc
					(start 1.253811 0.524161)
					(mid 0.087542 -0.105784)
					(end -0.529126 -1.279127)
					(width 0.2)
				)
				(gr_arc
					(start 1.275473 0.621136)
					(mid 0.0309 -0.033527)
					(end -0.621807 -1.279127)
					(width 0.2)
				)
				(gr_arc
					(start 1.263664 0.711602)
					(mid -0.037759 0.026651)
					(end -0.71437 -1.279127)
					(width 0.2)
				)
				(gr_arc
					(start 1.253435 0.802342)
					(mid -0.105837 0.087395)
					(end -0.806826 -1.279127)
					(width 0.2)
				)
				(gr_arc
					(start 1.267475 0.897258)
					(mid -0.165236 0.156885)
					(end -0.899187 -1.279127)
					(width 0.2)
				)
				(gr_arc
					(start 1.270645 0.990112)
					(mid -0.228522 0.222449)
					(end -0.991463 -1.279127)
					(width 0.2)
				)
				(gr_arc
					(start 1.266278 1.081674)
					(mid -0.294507 0.285313)
					(end -1.083663 -1.279127)
					(width 0.2)
				)
				(gr_line
					(start 1.279127 0.250195)
					(end 1.279127 1.083663)
					(width 0.2)
				)
				(gr_line
					(start -0.250195 -1.279127)
					(end -1.083663 -1.279127)
					(width 0.2)
				)
			)
		)
		(pad "1" thru_hole circle
			(at 0 0 180)
			(size 6 6)
			(drill 3.7)
			(layers "*.Cu" "*.Mask")
			(remove_unused_layers no)
			(net 1 "GND")
			(pintype "passive")
		)
	)
	(footprint "antmicro-footprints:C_0402_1005Metric"
		(layer "B.Cu")
		(at 141.224 84.582 45)
		(descr "Capacitor SMD 0402")
		(tags "capacitor SMD 0402")
		(property "Reference" "C55"
			(at -3.792854 -0.017147 45)
			(layer "B.SilkS")
			(effects
				(font
					(size 0.7 0.7)
					(thickness 0.15)
				)
				(justify right bottom mirror)
			)
		)
		(property "Value" "C_10u_0402"
			(at -1.022927 -2.155213 45)
			(layer "B.Fab")
			(effects
				(font
					(size 0.7 0.7)
					(thickness 0.15)
				)
				(justify right bottom mirror)
			)
		)
		(property "Datasheet" "https://www.yageo.com/en/Chart/Download/pdf/CC0402MRX5R5BB106"
			(at 0 0 45)
			(layer "F.Fab")
			(hide yes)
			(effects
				(font
					(size 1.27 1.27)
					(thickness 0.15)
				)
			)
		)
		(property "Description" "SMD Multilayer Ceramic Capacitor, 10 µF, 6.3 V, 0402 [1005 Metric], ± 20%, X5R, CC Series"
			(at 0 0 45)
			(layer "F.Fab")
			(hide yes)
			(effects
				(font
					(size 1.27 1.27)
					(thickness 0.15)
				)
			)
		)
		(property "Author" "Antmicro"
			(at 101.172058 -75.086954 0)
			(layer "B.Fab")
			(hide yes)
			(effects
				(font
					(size 1 1)
					(thickness 0.15)
				)
				(justify mirror)
			)
		)
		(property "Dielectric" ""
			(at 101.172058 -75.086954 0)
			(layer "B.Fab")
			(hide yes)
			(effects
				(font
					(size 1 1)
					(thickness 0.15)
				)
				(justify mirror)
			)
		)
		(property "License" "Apache-2.0"
			(at 101.172058 -75.086954 0)
			(layer "B.Fab")
			(hide yes)
			(effects
				(font
					(size 1 1)
					(thickness 0.15)
				)
				(justify mirror)
			)
		)
		(property "MPN" "CC0402MRX5R5BB106"
			(at 101.172058 -75.086954 0)
			(layer "B.Fab")
			(hide yes)
			(effects
				(font
					(size 1 1)
					(thickness 0.15)
				)
				(justify mirror)
			)
		)
		(property "Manufacturer" "YAGEO"
			(at 101.172058 -75.086954 0)
			(layer "B.Fab")
			(hide yes)
			(effects
				(font
					(size 1 1)
					(thickness 0.15)
				)
				(justify mirror)
			)
		)
		(property "Val" "10u"
			(at 101.172058 -75.086954 0)
			(layer "B.Fab")
			(hide yes)
			(effects
				(font
					(size 1 1)
					(thickness 0.15)
				)
				(justify mirror)
			)
		)
		(property "Voltage" ""
			(at 101.172058 -75.086954 0)
			(layer "B.Fab")
			(hide yes)
			(effects
				(font
					(size 1 1)
					(thickness 0.15)
				)
				(justify mirror)
			)
		)
		(sheetname "/Deserializer/")
		(sheetfile "deserializer.kicad_sch")
		(attr smd)
		(fp_poly
			(pts
				(xy -0.925 0.47) (xy 0.925 0.47) (xy 0.925 -0.47) (xy -0.925 -0.47)
			)
			(stroke
				(width 0.05)
				(type default)
			)
			(fill no)
			(layer "B.CrtYd")
		)
		(fp_line
			(start -0.494 -0.248)
			(end 0.504 -0.248)
			(stroke
				(width 0.15)
				(type solid)
			)
			(layer "B.Fab")
		)
		(fp_line
			(start -0.494 0.25)
			(end -0.494 -0.248)
			(stroke
				(width 0.15)
				(type solid)
			)
			(layer "B.Fab")
		)
		(fp_line
			(start 0.504 -0.248)
			(end 0.504 0.25)
			(stroke
				(width 0.15)
				(type solid)
			)
			(layer "B.Fab")
		)
		(fp_line
			(start 0.504 0.25)
			(end -0.494 0.25)
			(stroke
				(width 0.15)
				(type solid)
			)
			(layer "B.Fab")
		)
		(pad "1" smd roundrect
			(at -0.48 0 45)
			(size 0.59 0.64)
			(layers "B.Cu" "B.Mask" "B.Paste")
			(roundrect_rratio 0.25)
			(net 1 "GND")
			(pintype "passive")
		)
		(pad "2" smd roundrect
			(at 0.48 0 45)
			(size 0.59 0.64)
			(layers "B.Cu" "B.Mask" "B.Paste")
			(roundrect_rratio 0.25)
			(net 29 "/Deserializer/VTERM")
			(pintype "passive")
		)
	)
)
